(kicad_pcb
	(version 20260206)
	(generator "pcbnew")
	(generator_version "10.0")
	(general
		(thickness 1.6)
		(legacy_teardrops no)
	)
	(paper "A4")
	(title_block
		(title "dpb — 14545-sa.0730WZS0815.brd")
		(comment 1 "Honey Badger (Wiwynn) / footprints 109-115 of 1066")
	)
	(layers
		(0 "F.Cu" signal "TOP")
		(4 "In1.Cu" signal "L2GND")
		(6 "In2.Cu" signal "L3")
		(8 "In3.Cu" signal "L4VCC")
		(10 "In4.Cu" signal "L5VCC")
		(12 "In5.Cu" signal "L6")
		(14 "In6.Cu" signal "L7GND")
		(2 "B.Cu" signal "BOTTOM")
		(9 "F.Adhes" user "F.Adhesive")
		(11 "B.Adhes" user "B.Adhesive")
		(13 "F.Paste" user "Package Geometry/Pastemask Top")
		(15 "B.Paste" user "Package Geometry/Pastemask Bottom")
		(5 "F.SilkS" user "Ref Des/Silkscreen Top")
		(7 "B.SilkS" user "Ref Des/Silkscreen Bottom")
		(1 "F.Mask" user "Board Geometry/Soldermask Top")
		(3 "B.Mask" user "Board Geometry/Soldermask Bottom")
		(17 "Dwgs.User" user "User.Drawings")
		(19 "Cmts.User" user "User.Comments")
		(21 "Eco1.User" user "User.Eco1")
		(23 "Eco2.User" user "User.Eco2")
		(25 "Edge.Cuts" user "Board Geometry/Outline")
		(27 "Margin" user)
		(31 "F.CrtYd" user "Package Geometry/Place Bound Top")
		(29 "B.CrtYd" user "Package Geometry/Place Bound Bottom")
		(35 "F.Fab" user "Ref Des/Assembly Top")
		(33 "B.Fab" user "Ref Des/Assembly Bottom")
	)
	(footprint ""
		(layer "F.Cu")
		(at 217.762582 -263.116568 -90)
		(property "Reference" "C134"
			(at 0 0 270)
			(layer "F.SilkS")
			(hide yes)
			(effects
				(font
					(size 1.27 1.27)
				)
			)
		)
		(property "Value" "SCD01U50V2KX-1GP"
			(at 1.1811 -2.7051 270)
			(unlocked yes)
			(layer "F.Fab")
			(hide yes)
			(effects
				(font
					(size 1.016 1.016)
					(thickness 0.1524)
				)
			)
		)
		(property "Device Type" "C402H22"
			(at 1.1811 -4.2291 270)
			(unlocked yes)
			(layer "F.Fab")
			(hide yes)
			(effects
				(font
					(size 1.016 1.016)
					(thickness 0.1524)
				)
			)
		)
		(duplicate_pad_numbers_are_jumpers no)
		(fp_rect
			(start -0.4318 0.9525)
			(end 0.4318 -0.9525)
			(stroke
				(width 0)
				(type default)
			)
			(fill no)
			(layer "F.CrtYd")
		)
		(fp_rect
			(start -0.4318 0.9525)
			(end 0.4318 -0.9525)
			(stroke
				(width 0)
				(type default)
			)
			(fill no)
			(layer "F.Fab")
		)
		(pad "1" smd custom
			(at 0 -0.4445 270)
			(size 0.1524 0.1524)
			(layers "F.Cu" "F.Mask" "F.Paste")
			(net "SAS2X28_DRIVE_RX_N_A2")
			(options
				(clearance outline)
				(anchor circle)
			)
			(primitives
				(gr_poly
					(pts
						(arc
							(start 0.3048 -0.2032)
							(mid 0.275042 -0.275042)
							(end 0.2032 -0.3048)
						)
						(arc
							(start -0.2032 -0.3048)
							(mid -0.275042 -0.275042)
							(end -0.3048 -0.2032)
						)
						(arc
							(start -0.3048 0.2032)
							(mid -0.275042 0.275042)
							(end -0.2032 0.3048)
						)
						(arc
							(start 0.2032 0.3048)
							(mid 0.275042 0.275042)
							(end 0.3048 0.2032)
						)
					)
					(width 0)
					(fill yes)
				)
			)
		)
		(pad "2" smd custom
			(at 0 0.4445 270)
			(size 0.1524 0.1524)
			(layers "F.Cu" "F.Mask" "F.Paste")
			(net "SAS2X28_A_HDD2_RX_-")
			(options
				(clearance outline)
				(anchor circle)
			)
			(primitives
				(gr_poly
					(pts
						(arc
							(start 0.3048 -0.2032)
							(mid 0.275042 -0.275042)
							(end 0.2032 -0.3048)
						)
						(arc
							(start -0.2032 -0.3048)
							(mid -0.275042 -0.275042)
							(end -0.3048 -0.2032)
						)
						(arc
							(start -0.3048 0.2032)
							(mid -0.275042 0.275042)
							(end -0.2032 0.3048)
						)
						(arc
							(start 0.2032 0.3048)
							(mid 0.275042 0.275042)
							(end 0.3048 0.2032)
						)
					)
					(width 0)
					(fill yes)
				)
			)
		)
	)
	(footprint ""
		(layer "F.Cu")
		(at 200.146412 -88.753696 -90)
		(property "Reference" "U14"
			(at 0 0 270)
			(layer "F.SilkS")
			(hide yes)
			(effects
				(font
					(size 1.27 1.27)
				)
			)
		)
		(property "Value" "P2003EVG-GP"
			(at 0 -11.1252 270)
			(unlocked yes)
			(layer "F.Fab")
			(hide yes)
			(effects
				(font
					(size 1.016 1.016)
					(thickness 0.1524)
				)
			)
		)
		(property "Device Type" "SOIC8H79"
			(at 0 -12.6492 270)
			(unlocked yes)
			(layer "F.Fab")
			(hide yes)
			(effects
				(font
					(size 1.016 1.016)
					(thickness 0.1524)
				)
			)
		)
		(duplicate_pad_numbers_are_jumpers no)
		(fp_line
			(start -2.6162 3.429)
			(end -2.6162 1.4732)
			(stroke
				(width 0.4064)
				(type default)
			)
			(layer "F.SilkS")
		)
		(fp_line
			(start -2.7432 1.4224)
			(end 2.1336 1.4224)
			(stroke
				(width 0.1524)
				(type default)
			)
			(layer "F.SilkS")
		)
		(fp_line
			(start 2.1336 1.4224)
			(end 2.1336 -1.4224)
			(stroke
				(width 0.1524)
				(type default)
			)
			(layer "F.SilkS")
		)
		(fp_line
			(start -2.2352 0)
			(end -2.7432 0.508)
			(stroke
				(width 0.1524)
				(type default)
			)
			(layer "F.SilkS")
		)
		(fp_line
			(start -2.7432 -0.508)
			(end -2.2352 0)
			(stroke
				(width 0.1524)
				(type default)
			)
			(layer "F.SilkS")
		)
		(fp_line
			(start -2.7432 -1.4224)
			(end -2.7432 1.4224)
			(stroke
				(width 0.1524)
				(type default)
			)
			(layer "F.SilkS")
		)
		(fp_line
			(start 2.1336 -1.4224)
			(end -2.7432 -1.4224)
			(stroke
				(width 0.1524)
				(type default)
			)
			(layer "F.SilkS")
		)
		(fp_poly
			(pts
				(xy 2.2098 -1.4224) (xy 2.2098 1.4224) (xy -2.2225 1.4224) (xy -2.2225 -1.4224)
			)
			(stroke
				(width 0)
				(type default)
			)
			(fill yes)
			(layer "F.SilkS")
		)
		(fp_rect
			(start -2.4511 2.9972)
			(end 2.4511 -2.9972)
			(stroke
				(width 0)
				(type default)
			)
			(fill no)
			(layer "F.CrtYd")
		)
		(fp_poly
			(pts
				(xy -2.8194 3.6322) (xy -2.8194 -3.6322) (xy 2.8194 -3.6322) (xy 2.8194 -2.2987) (xy 2.4511 -2.2987)
				(xy 2.4511 -2.9972) (xy -2.4511 -2.9972) (xy -2.4511 2.9972) (xy 2.4511 2.9972) (xy 2.4511 -2.286)
				(xy 2.8194 -2.286) (xy 2.8194 3.6322)
			)
			(stroke
				(width 0)
				(type default)
			)
			(fill no)
			(layer "F.CrtYd")
		)
		(fp_rect
			(start -2.8194 3.6322)
			(end 2.8194 -3.6322)
			(stroke
				(width 0)
				(type default)
			)
			(fill no)
			(layer "F.Fab")
		)
		(pad "1" smd rect
			(at -1.905 2.54 270)
			(size 0.635 1.651)
			(layers "F.Cu" "F.Mask" "F.Paste")
			(net "P12V")
		)
		(pad "2" smd rect
			(at -0.635 2.54 270)
			(size 0.635 1.651)
			(layers "F.Cu" "F.Mask" "F.Paste")
			(net "P12V")
		)
		(pad "3" smd rect
			(at 0.635 2.54 270)
			(size 0.635 1.651)
			(layers "F.Cu" "F.Mask" "F.Paste")
			(net "P12V")
		)
		(pad "4" smd rect
			(at 1.905 2.54 270)
			(size 0.635 1.651)
			(layers "F.Cu" "F.Mask" "F.Paste")
			(net "SW_HDD4_N")
		)
		(pad "5" smd rect
			(at 1.905 -2.54 270)
			(size 0.635 1.651)
			(layers "F.Cu" "F.Mask" "F.Paste")
			(net "P12V_HDD4")
		)
		(pad "6" smd rect
			(at 0.635 -2.54 270)
			(size 0.635 1.651)
			(layers "F.Cu" "F.Mask" "F.Paste")
			(net "P12V_HDD4")
		)
		(pad "7" smd rect
			(at -0.635 -2.54 270)
			(size 0.635 1.651)
			(layers "F.Cu" "F.Mask" "F.Paste")
			(net "P12V_HDD4")
		)
		(pad "8" smd rect
			(at -1.905 -2.54 270)
			(size 0.635 1.651)
			(layers "F.Cu" "F.Mask" "F.Paste")
			(net "P12V_HDD4")
		)
	)
	(footprint ""
		(layer "F.Cu")
		(at 49.021746 -349.7707 90)
		(property "Reference" "R186"
			(at 0 0 90)
			(layer "F.SilkS")
			(hide yes)
			(effects
				(font
					(size 1.27 1.27)
				)
			)
		)
		(property "Value" "0R2J-2-GP"
			(at 0.064008 -3.993896 90)
			(unlocked yes)
			(layer "F.Fab")
			(hide yes)
			(effects
				(font
					(size 1.016 1.016)
					(thickness 0.1524)
				)
			)
		)
		(property "Device Type" "R402H16"
			(at 0.064008 -5.517896 90)
			(unlocked yes)
			(layer "F.Fab")
			(hide yes)
			(effects
				(font
					(size 1.016 1.016)
					(thickness 0.1524)
				)
			)
		)
		(duplicate_pad_numbers_are_jumpers no)
		(fp_line
			(start 0.508 -0.9398)
			(end -0.508 -0.9398)
			(stroke
				(width 0.1524)
				(type default)
			)
			(layer "F.SilkS")
		)
		(fp_line
			(start -0.508 -0.9398)
			(end -0.508 0.9398)
			(stroke
				(width 0.1524)
				(type default)
			)
			(layer "F.SilkS")
		)
		(fp_rect
			(start -0.508 0.9398)
			(end 0.508 -0.9398)
			(stroke
				(width 0)
				(type default)
			)
			(fill no)
			(layer "F.CrtYd")
		)
		(fp_rect
			(start -0.508 0.9398)
			(end 0.508 -0.9398)
			(stroke
				(width 0)
				(type default)
			)
			(fill no)
			(layer "F.Fab")
		)
		(pad "1" smd custom
			(at 0 -0.4445 90)
			(size 0.1397 0.1397)
			(layers "F.Cu" "F.Mask" "F.Paste")
			(net "DRV_ACT_NET6")
			(options
				(clearance outline)
				(anchor circle)
			)
			(primitives
				(gr_poly
					(pts
						(arc
							(start -0.1778 -0.2794)
							(mid -0.249642 -0.249642)
							(end -0.2794 -0.1778)
						)
						(arc
							(start -0.2794 0.1778)
							(mid -0.249642 0.249642)
							(end -0.1778 0.2794)
						)
						(arc
							(start 0.1778 0.2794)
							(mid 0.249642 0.249642)
							(end 0.2794 0.1778)
						)
						(arc
							(start 0.2794 -0.1778)
							(mid 0.249642 -0.249642)
							(end 0.1778 -0.2794)
						)
					)
					(width 0)
					(fill yes)
				)
			)
		)
		(pad "2" smd custom
			(at 0 0.4445 90)
			(size 0.1397 0.1397)
			(layers "F.Cu" "F.Mask" "F.Paste")
			(net "DRIVE_ACT_6")
			(options
				(clearance outline)
				(anchor circle)
			)
			(primitives
				(gr_poly
					(pts
						(arc
							(start -0.1778 -0.2794)
							(mid -0.249642 -0.249642)
							(end -0.2794 -0.1778)
						)
						(arc
							(start -0.2794 0.1778)
							(mid -0.249642 0.249642)
							(end -0.1778 0.2794)
						)
						(arc
							(start 0.1778 0.2794)
							(mid 0.249642 0.249642)
							(end 0.2794 0.1778)
						)
						(arc
							(start 0.2794 -0.1778)
							(mid 0.249642 -0.249642)
							(end 0.1778 -0.2794)
						)
					)
					(width 0)
					(fill yes)
				)
			)
		)
	)
	(footprint ""
		(layer "F.Cu")
		(at 31.495746 -441.099702 180)
		(property "Reference" "C261"
			(at 0 0 180)
			(layer "F.SilkS")
			(hide yes)
			(effects
				(font
					(size 1.27 1.27)
				)
			)
		)
		(property "Value" "SCD1U10V2KX-5GP"
			(at 1.1811 -2.7051 180)
			(unlocked yes)
			(layer "F.Fab")
			(hide yes)
			(effects
				(font
					(size 1.016 1.016)
					(thickness 0.1524)
				)
			)
		)
		(property "Device Type" "C402H22"
			(at 1.1811 -4.2291 180)
			(unlocked yes)
			(layer "F.Fab")
			(hide yes)
			(effects
				(font
					(size 1.016 1.016)
					(thickness 0.1524)
				)
			)
		)
		(duplicate_pad_numbers_are_jumpers no)
		(fp_rect
			(start -0.4318 0.9525)
			(end 0.4318 -0.9525)
			(stroke
				(width 0)
				(type default)
			)
			(fill no)
			(layer "F.CrtYd")
		)
		(fp_rect
			(start -0.4318 0.9525)
			(end 0.4318 -0.9525)
			(stroke
				(width 0)
				(type default)
			)
			(fill no)
			(layer "F.Fab")
		)
		(pad "1" smd custom
			(at 0 -0.4445 180)
			(size 0.1524 0.1524)
			(layers "F.Cu" "F.Mask" "F.Paste")
			(net "P3V3")
			(options
				(clearance outline)
				(anchor circle)
			)
			(primitives
				(gr_poly
					(pts
						(arc
							(start 0.3048 -0.2032)
							(mid 0.275042 -0.275042)
							(end 0.2032 -0.3048)
						)
						(arc
							(start -0.2032 -0.3048)
							(mid -0.275042 -0.275042)
							(end -0.3048 -0.2032)
						)
						(arc
							(start -0.3048 0.2032)
							(mid -0.275042 0.275042)
							(end -0.2032 0.3048)
						)
						(arc
							(start 0.2032 0.3048)
							(mid 0.275042 0.275042)
							(end 0.3048 0.2032)
						)
					)
					(width 0)
					(fill yes)
				)
			)
		)
		(pad "2" smd custom
			(at 0 0.4445 180)
			(size 0.1524 0.1524)
			(layers "F.Cu" "F.Mask" "F.Paste")
			(net "GND")
			(options
				(clearance outline)
				(anchor circle)
			)
			(primitives
				(gr_poly
					(pts
						(arc
							(start 0.3048 -0.2032)
							(mid 0.275042 -0.275042)
							(end 0.2032 -0.3048)
						)
						(arc
							(start -0.2032 -0.3048)
							(mid -0.275042 -0.275042)
							(end -0.3048 -0.2032)
						)
						(arc
							(start -0.3048 0.2032)
							(mid -0.275042 0.275042)
							(end -0.2032 0.3048)
						)
						(arc
							(start 0.2032 0.3048)
							(mid 0.275042 0.275042)
							(end 0.3048 0.2032)
						)
					)
					(width 0)
					(fill yes)
				)
			)
		)
	)
	(footprint ""
		(layer "F.Cu")
		(at 45.482256 -452.783702 90)
		(property "Reference" "R172"
			(at 0 0 90)
			(layer "F.SilkS")
			(hide yes)
			(effects
				(font
					(size 1.27 1.27)
				)
			)
		)
		(property "Value" "0R2J-2-GP"
			(at 0.064008 -3.993896 90)
			(unlocked yes)
			(layer "F.Fab")
			(hide yes)
			(effects
				(font
					(size 1.016 1.016)
					(thickness 0.1524)
				)
			)
		)
		(property "Device Type" "R402H16"
			(at 0.064008 -5.517896 90)
			(unlocked yes)
			(layer "F.Fab")
			(hide yes)
			(effects
				(font
					(size 1.016 1.016)
					(thickness 0.1524)
				)
			)
		)
		(duplicate_pad_numbers_are_jumpers no)
		(fp_line
			(start 0.508 -0.9398)
			(end -0.508 -0.9398)
			(stroke
				(width 0.1524)
				(type default)
			)
			(layer "F.SilkS")
		)
		(fp_line
			(start -0.508 -0.9398)
			(end -0.508 0.9398)
			(stroke
				(width 0.1524)
				(type default)
			)
			(layer "F.SilkS")
		)
		(fp_rect
			(start -0.508 0.9398)
			(end 0.508 -0.9398)
			(stroke
				(width 0)
				(type default)
			)
			(fill no)
			(layer "F.CrtYd")
		)
		(fp_rect
			(start -0.508 0.9398)
			(end 0.508 -0.9398)
			(stroke
				(width 0)
				(type default)
			)
			(fill no)
			(layer "F.Fab")
		)
		(pad "1" smd custom
			(at 0 -0.4445 90)
			(size 0.1397 0.1397)
			(layers "F.Cu" "F.Mask" "F.Paste")
			(net "DRV_ACT_NET5")
			(options
				(clearance outline)
				(anchor circle)
			)
			(primitives
				(gr_poly
					(pts
						(arc
							(start -0.1778 -0.2794)
							(mid -0.249642 -0.249642)
							(end -0.2794 -0.1778)
						)
						(arc
							(start -0.2794 0.1778)
							(mid -0.249642 0.249642)
							(end -0.1778 0.2794)
						)
						(arc
							(start 0.1778 0.2794)
							(mid 0.249642 0.249642)
							(end 0.2794 0.1778)
						)
						(arc
							(start 0.2794 -0.1778)
							(mid 0.249642 -0.249642)
							(end 0.1778 -0.2794)
						)
					)
					(width 0)
					(fill yes)
				)
			)
		)
		(pad "2" smd custom
			(at 0 0.4445 90)
			(size 0.1397 0.1397)
			(layers "F.Cu" "F.Mask" "F.Paste")
			(net "DRIVE_ACT_5")
			(options
				(clearance outline)
				(anchor circle)
			)
			(primitives
				(gr_poly
					(pts
						(arc
							(start -0.1778 -0.2794)
							(mid -0.249642 -0.249642)
							(end -0.2794 -0.1778)
						)
						(arc
							(start -0.2794 0.1778)
							(mid -0.249642 0.249642)
							(end -0.1778 0.2794)
						)
						(arc
							(start 0.1778 0.2794)
							(mid 0.249642 0.249642)
							(end 0.2794 0.1778)
						)
						(arc
							(start 0.2794 -0.1778)
							(mid 0.249642 -0.249642)
							(end 0.1778 -0.2794)
						)
					)
					(width 0)
					(fill yes)
				)
			)
		)
	)
	(footprint ""
		(layer "F.Cu")
		(at 216.110058 -385.520184 180)
		(property "Reference" "C123"
			(at 0 0 180)
			(layer "F.SilkS")
			(hide yes)
			(effects
				(font
					(size 1.27 1.27)
				)
			)
		)
		(property "Value" "SC10U16V6KX-2GP"
			(at -0.0762 -5.1308 180)
			(unlocked yes)
			(layer "F.Fab")
			(hide yes)
			(effects
				(font
					(size 1.016 1.016)
					(thickness 0.1524)
				)
			)
		)
		(property "Device Type" "C1206H71"
			(at -0.127 -6.6548 180)
			(unlocked yes)
			(layer "F.Fab")
			(hide yes)
			(effects
				(font
					(size 1.016 1.016)
					(thickness 0.1524)
				)
			)
		)
		(duplicate_pad_numbers_are_jumpers no)
		(fp_line
			(start 1.016 2.2352)
			(end -1.016 2.2352)
			(stroke
				(width 0.1524)
				(type default)
			)
			(layer "F.SilkS")
		)
		(fp_line
			(start 1.016 0.8382)
			(end 1.016 2.2352)
			(stroke
				(width 0.1524)
				(type default)
			)
			(layer "F.SilkS")
		)
		(fp_line
			(start 1.016 -2.2352)
			(end 1.016 -0.8382)
			(stroke
				(width 0.1524)
				(type default)
			)
			(layer "F.SilkS")
		)
		(fp_line
			(start -1.016 2.2352)
			(end -1.016 0.8382)
			(stroke
				(width 0.1524)
				(type default)
			)
			(layer "F.SilkS")
		)
		(fp_line
			(start -1.016 -0.8382)
			(end -1.016 -2.2352)
			(stroke
				(width 0.1524)
				(type default)
			)
			(layer "F.SilkS")
		)
		(fp_line
			(start -1.016 -2.2352)
			(end 1.016 -2.2352)
			(stroke
				(width 0.1524)
				(type default)
			)
			(layer "F.SilkS")
		)
		(fp_rect
			(start -1.0922 2.3114)
			(end 1.0922 -2.3114)
			(stroke
				(width 0)
				(type default)
			)
			(fill no)
			(layer "F.CrtYd")
		)
		(fp_poly
			(pts
				(xy 1.0922 -2.3114) (xy 1.0922 2.3114) (xy -1.0922 2.3114) (xy -1.0922 -2.3114)
			)
			(stroke
				(width 0)
				(type default)
			)
			(fill no)
			(layer "F.Fab")
		)
		(pad "1" smd rect
			(at 0 -1.397 180)
			(size 1.651 1.27)
			(layers "F.Cu" "F.Mask" "F.Paste")
			(net "P5V_HDD1")
		)
		(pad "2" smd rect
			(at 0 1.397 180)
			(size 1.651 1.27)
			(layers "F.Cu" "F.Mask" "F.Paste")
			(net "GND")
		)
	)
	(footprint ""
		(layer "F.Cu")
		(at 4.49961 -483.399846)
		(property "Reference" "H2"
			(at 0 0 0)
			(layer "F.SilkS")
			(hide yes)
			(effects
				(font
					(size 1.27 1.27)
				)
			)
		)
		(property "Value" "HOLE315R140"
			(at 0 -7.5692 0)
			(unlocked yes)
			(layer "F.Fab")
			(hide yes)
			(effects
				(font
					(size 1.016 1.016)
					(thickness 0.1524)
				)
			)
		)
		(property "Device Type" "HOLE315R140"
			(at 0 -9.0932 0)
			(unlocked yes)
			(layer "F.Fab")
			(hide yes)
			(effects
				(font
					(size 1.016 1.016)
					(thickness 0.1524)
				)
			)
		)
		(duplicate_pad_numbers_are_jumpers no)
		(fp_poly
			(pts
				(arc
					(start 4.3053 0)
					(mid -4.3053 0)
					(end 4.3053 0)
				)
			)
			(stroke
				(width 0)
				(type default)
			)
			(fill no)
			(layer "F.CrtYd")
		)
		(fp_poly
			(pts
				(arc
					(start 4.3053 0)
					(mid -4.3053 0)
					(end 4.3053 0)
				)
			)
			(stroke
				(width 0)
				(type default)
			)
			(fill no)
			(layer "F.Fab")
		)
		(pad "1" thru_hole circle
			(at 0.00127 0.00127)
			(size 8.001 8.001)
			(drill 3.556)
			(layers "*.Cu" "*.Mask")
			(remove_unused_layers no)
			(net "GND")
			(clearance -1.7145)
			(thermal_gap 0.3048)
			(padstack
				(mode front_inner_back)
				(layer "Inner"
					(shape circle)
					(size 3.9624 3.9624)
					(clearance 0.3048)
				)
				(layer "B.Cu"
					(shape circle)
					(size 8.001 8.001)
					(clearance -1.7145)
				)
			)
		)
	)
)
